(kicad_pcb
	(version 20260206)
	(generator "pcbnew")
	(generator_version "10.0")
	(general
		(thickness 1.6)
		(legacy_teardrops no)
	)
	(paper "A4")
	(title_block
		(title "pdpb — Lightning_PDPB_BRD.brd")
		(comment 1 "Lightning (Wiwynn / Facebook NVMe JBOF) / footprints 436-436 of 1140")
	)
	(layers
		(0 "F.Cu" signal "TOP")
		(4 "In1.Cu" signal "L2GND")
		(6 "In2.Cu" signal "L3")
		(8 "In3.Cu" signal "L4VCC")
		(10 "In4.Cu" signal "L5VCC")
		(12 "In5.Cu" signal "L6")
		(14 "In6.Cu" signal "L7GND")
		(2 "B.Cu" signal "BOTTOM")
		(9 "F.Adhes" user "F.Adhesive")
		(11 "B.Adhes" user "B.Adhesive")
		(13 "F.Paste" user "Package Geometry/Pastemask Top")
		(15 "B.Paste" user "Package Geometry/Pastemask Bottom")
		(5 "F.SilkS" user "Ref Des/Silkscreen Top")
		(7 "B.SilkS" user "Ref Des/Silkscreen Bottom")
		(1 "F.Mask" user "Board Geometry/Soldermask Top")
		(3 "B.Mask" user "Board Geometry/Soldermask Bottom")
		(17 "Dwgs.User" user "User.Drawings")
		(19 "Cmts.User" user "User.Comments")
		(21 "Eco1.User" user "User.Eco1")
		(23 "Eco2.User" user "User.Eco2")
		(25 "Edge.Cuts" user "Board Geometry/Outline")
		(27 "Margin" user)
		(31 "F.CrtYd" user "Package Geometry/Place Bound Top")
		(29 "B.CrtYd" user "Package Geometry/Place Bound Bottom")
		(35 "F.Fab" user "Ref Des/Assembly Top")
		(33 "B.Fab" user "Ref Des/Assembly Bottom")
	)
	(footprint ""
		(layer "F.Cu")
		(at 226.149916 -479.67011 90)
		(property "Reference" "J100"
			(at 0 0 90)
			(layer "F.SilkS")
			(hide yes)
			(effects
				(font
					(size 1.27 1.27)
				)
			)
		)
		(property "Value" "PCISLT68-14-GP-U1"
			(at -22.225 12.7508 90)
			(unlocked yes)
			(layer "F.Fab")
			(hide yes)
			(effects
				(font
					(size 1.016 1.016)
					(thickness 0.1524)
				)
			)
		)
		(property "Device Type" "SD-78827-0001"
			(at -22.225 11.2268 90)
			(unlocked yes)
			(layer "F.Fab")
			(hide yes)
			(effects
				(font
					(size 1.016 1.016)
					(thickness 0.1524)
				)
			)
		)
		(duplicate_pad_numbers_are_jumpers no)
		(fp_line
			(start 20.4724 -3.4036)
			(end 20.4724 0.0254)
			(stroke
				(width 0.1524)
				(type default)
			)
			(layer "F.SilkS")
		)
		(fp_line
			(start -20.4724 -3.4036)
			(end 20.4724 -3.4036)
			(stroke
				(width 0.1524)
				(type default)
			)
			(layer "F.SilkS")
		)
		(fp_line
			(start 23.749 0.0254)
			(end 23.749 4.6736)
			(stroke
				(width 0.1524)
				(type default)
			)
			(layer "F.SilkS")
		)
		(fp_line
			(start 20.4724 0.0254)
			(end 23.749 0.0254)
			(stroke
				(width 0.1524)
				(type default)
			)
			(layer "F.SilkS")
		)
		(fp_line
			(start -20.4724 0.0254)
			(end -20.4724 -3.4036)
			(stroke
				(width 0.1524)
				(type default)
			)
			(layer "F.SilkS")
		)
		(fp_line
			(start -23.749 0.0254)
			(end -20.4724 0.0254)
			(stroke
				(width 0.1524)
				(type default)
			)
			(layer "F.SilkS")
		)
		(fp_line
			(start 23.117556 1.803908)
			(end 23.117556 2.896108)
			(stroke
				(width 0.3048)
				(type default)
			)
			(layer "F.SilkS")
		)
		(fp_line
			(start -20.882356 1.803908)
			(end -20.882356 2.896108)
			(stroke
				(width 0.3048)
				(type default)
			)
			(layer "F.SilkS")
		)
		(fp_line
			(start 20.882356 2.896108)
			(end 20.882356 1.803908)
			(stroke
				(width 0.3048)
				(type default)
			)
			(layer "F.SilkS")
		)
		(fp_line
			(start -23.117556 2.896108)
			(end -23.117556 1.803908)
			(stroke
				(width 0.3048)
				(type default)
			)
			(layer "F.SilkS")
		)
		(fp_line
			(start 23.749 4.6736)
			(end 20.4724 4.6736)
			(stroke
				(width 0.1524)
				(type default)
			)
			(layer "F.SilkS")
		)
		(fp_line
			(start 20.4724 4.6736)
			(end 20.4724 12.0142)
			(stroke
				(width 0.1524)
				(type default)
			)
			(layer "F.SilkS")
		)
		(fp_line
			(start -20.4724 4.6736)
			(end -23.749 4.6736)
			(stroke
				(width 0.1524)
				(type default)
			)
			(layer "F.SilkS")
		)
		(fp_line
			(start -23.749 4.6736)
			(end -23.749 0.0254)
			(stroke
				(width 0.1524)
				(type default)
			)
			(layer "F.SilkS")
		)
		(fp_line
			(start 17.8435 10.3124)
			(end -17.8435 10.3124)
			(stroke
				(width 0.1524)
				(type default)
			)
			(layer "F.SilkS")
		)
		(fp_line
			(start -17.8435 10.3124)
			(end -17.8435 12.0142)
			(stroke
				(width 0.1524)
				(type default)
			)
			(layer "F.SilkS")
		)
		(fp_line
			(start 20.4724 12.0142)
			(end 17.8435 12.0142)
			(stroke
				(width 0.1524)
				(type default)
			)
			(layer "F.SilkS")
		)
		(fp_line
			(start 17.8435 12.0142)
			(end 17.8435 10.3124)
			(stroke
				(width 0.1524)
				(type default)
			)
			(layer "F.SilkS")
		)
		(fp_line
			(start -17.8435 12.0142)
			(end -20.4724 12.0142)
			(stroke
				(width 0.1524)
				(type default)
			)
			(layer "F.SilkS")
		)
		(fp_line
			(start -20.4724 12.0142)
			(end -20.4724 4.6736)
			(stroke
				(width 0.1524)
				(type default)
			)
			(layer "F.SilkS")
		)
		(fp_arc
			(start 20.882356 1.803908)
			(mid 21.999956 0.686308)
			(end 23.117556 1.803908)
			(stroke
				(width 0.3048)
				(type default)
			)
			(layer "F.SilkS")
		)
		(fp_arc
			(start -23.117556 1.803908)
			(mid -21.999956 0.686308)
			(end -20.882356 1.803908)
			(stroke
				(width 0.3048)
				(type default)
			)
			(layer "F.SilkS")
		)
		(fp_arc
			(start 23.117556 2.896108)
			(mid 21.999956 4.013708)
			(end 20.882356 2.896108)
			(stroke
				(width 0.3048)
				(type default)
			)
			(layer "F.SilkS")
		)
		(fp_arc
			(start -20.882356 2.896108)
			(mid -21.999956 4.013708)
			(end -23.117556 2.896108)
			(stroke
				(width 0.3048)
				(type default)
			)
			(layer "F.SilkS")
		)
		(fp_poly
			(pts
				(xy -20.2184 11.7602) (xy -20.2184 4.4196) (xy -23.495 4.4196) (xy -23.495 0.2794) (xy -20.2184 0.2794)
				(xy -20.2184 -3.1496) (xy 20.2184 -3.1496) (xy 20.2184 0.2794) (xy 23.495 0.2794) (xy 23.495 4.4196)
				(xy 20.2184 4.4196) (xy 20.2184 11.7602) (xy 18.0975 11.7602) (xy 18.0975 10.0584) (xy -18.0975 10.0584)
				(xy -18.0975 11.7602)
			)
			(stroke
				(width 0)
				(type default)
			)
			(fill no)
			(layer "F.CrtYd")
		)
		(fp_poly
			(pts
				(xy -21.2471 16.256) (xy -21.2471 4.9276) (xy -24.003 4.9276) (xy -24.003 -0.2286) (xy -20.7264 -0.2286)
				(xy -20.7264 -3.6576) (xy 20.7264 -3.6576) (xy 20.7264 -0.2286) (xy 24.003 -0.2286) (xy 24.003 -0.00635)
				(xy 20.2184 -0.00635) (xy 20.2184 -3.1496) (xy -20.2184 -3.1496) (xy -20.2184 0.2794) (xy -23.495 0.2794)
				(xy -23.495 4.4196) (xy -20.2184 4.4196) (xy -20.2184 11.7602) (xy -18.0975 11.7602) (xy -18.0975 10.0584)
				(xy 18.0975 10.0584) (xy 18.0975 11.7602) (xy 20.2184 11.7602) (xy 20.2184 4.4196) (xy 23.495 4.4196)
				(xy 23.495 0.2794) (xy 20.2184 0.2794) (xy 20.2184 0.00635) (xy 24.003 0.00635) (xy 24.003 4.9276)
				(xy 21.2471 4.9276) (xy 21.2471 16.256)
			)
			(stroke
				(width 0)
				(type default)
			)
			(fill no)
			(layer "F.CrtYd")
		)
		(fp_poly
			(pts
				(xy -21.2471 16.256) (xy -21.2471 4.9276) (xy -24.003 4.9276) (xy -24.003 -0.2286) (xy -20.7264 -0.2286)
				(xy -20.7264 -3.6576) (xy 20.7264 -3.6576) (xy 20.7264 -0.2286) (xy 24.003 -0.2286) (xy 24.003 4.9276)
				(xy 21.2471 4.9276) (xy 21.2471 16.256)
			)
			(stroke
				(width 0)
				(type default)
			)
			(fill no)
			(layer "F.Fab")
		)
		(pad "" np_thru_hole circle
			(at -18.999962 0 90)
			(size 0.254 0.254)
			(drill 1.8542)
			(layers "*.Cu" "*.Mask")
			(clearance 1.1557)
			(thermal_gap 1.1557)
		)
		(pad "" np_thru_hole circle
			(at 18.999962 0 90)
			(size 0.254 0.254)
			(drill 1.8542)
			(layers "*.Cu" "*.Mask")
			(clearance 1.1557)
			(thermal_gap 1.1557)
		)
		(pad "E1" smd rect
			(at -7.079996 1.240028 90)
			(size 0.508 2.0066)
			(layers "F.Cu" "F.Mask" "F.Paste")
			(net "PE_CLK100M_DR0_2_P")
		)
		(pad "E2" smd rect
			(at -6.279896 1.240028 90)
			(size 0.508 2.0066)
			(layers "F.Cu" "F.Mask" "F.Paste")
			(net "PE_CLK100M_DR0_2_N")
		)
		(pad "E3" smd rect
			(at -5.48005 1.240028 90)
			(size 0.508 2.0066)
			(layers "F.Cu" "F.Mask" "F.Paste")
			(net "P3V3")
		)
		(pad "E4" smd rect
			(at -4.67995 1.240028 90)
			(size 0.508 2.0066)
			(layers "F.Cu" "F.Mask" "F.Paste")
			(net "SSD0_PERST_N")
		)
		(pad "E5" smd rect
			(at -3.880104 1.240028 90)
			(size 0.508 2.0066)
			(layers "F.Cu" "F.Mask" "F.Paste")
			(net "SSD0_PERST_N")
		)
		(pad "E6" smd rect
			(at -3.080004 1.240028 90)
			(size 0.508 2.0066)
			(layers "F.Cu" "F.Mask" "F.Paste")
			(net "Net_17")
		)
		(pad "E7" smd rect
			(at -15.48003 -1.949958 90)
			(size 0.508 2.0066)
			(layers "F.Cu" "F.Mask" "F.Paste")
			(net "PE_CLK100M_DR0_1_P")
		)
		(pad "E8" smd rect
			(at -14.67993 -1.949958 90)
			(size 0.508 2.0066)
			(layers "F.Cu" "F.Mask" "F.Paste")
			(net "PE_CLK100M_DR0_1_N")
		)
		(pad "E9" smd rect
			(at -13.880084 -1.949958 90)
			(size 0.508 2.0066)
			(layers "F.Cu" "F.Mask" "F.Paste")
			(net "GND")
		)
		(pad "E10" smd rect
			(at -13.079984 -1.949958 90)
			(size 0.508 2.0066)
			(layers "F.Cu" "F.Mask" "F.Paste")
			(net "PE_TX1_DR0_N")
		)
		(pad "E11" smd rect
			(at -12.279884 -1.949958 90)
			(size 0.508 2.0066)
			(layers "F.Cu" "F.Mask" "F.Paste")
			(net "PE_TX1_DR0_P")
		)
		(pad "E12" smd rect
			(at -11.480038 -1.949958 90)
			(size 0.508 2.0066)
			(layers "F.Cu" "F.Mask" "F.Paste")
			(net "GND")
		)
		(pad "E13" smd rect
			(at -10.679938 -1.949958 90)
			(size 0.508 2.0066)
			(layers "F.Cu" "F.Mask" "F.Paste")
			(net "PE_RX1_DR0_N")
		)
		(pad "E14" smd rect
			(at -9.880092 -1.949958 90)
			(size 0.508 2.0066)
			(layers "F.Cu" "F.Mask" "F.Paste")
			(net "PE_RX1_DR0_P")
		)
		(pad "E15" smd rect
			(at -9.079992 -1.949958 90)
			(size 0.508 2.0066)
			(layers "F.Cu" "F.Mask" "F.Paste")
			(net "GND")
		)
		(pad "E16" smd rect
			(at -8.279892 -1.949958 90)
			(size 0.508 2.0066)
			(layers "F.Cu" "F.Mask" "F.Paste")
			(net "Net_24")
		)
		(pad "E17" smd rect
			(at 9.320022 -1.949958 90)
			(size 0.508 2.0066)
			(layers "F.Cu" "F.Mask" "F.Paste")
			(net "PE_TX4_DR0_N")
		)
		(pad "E18" smd rect
			(at 10.120122 -1.949958 90)
			(size 0.508 2.0066)
			(layers "F.Cu" "F.Mask" "F.Paste")
			(net "PE_TX4_DR0_P")
		)
		(pad "E19" smd rect
			(at 10.919968 -1.949958 90)
			(size 0.508 2.0066)
			(layers "F.Cu" "F.Mask" "F.Paste")
			(net "GND")
		)
		(pad "E20" smd rect
			(at 11.720068 -1.949958 90)
			(size 0.508 2.0066)
			(layers "F.Cu" "F.Mask" "F.Paste")
			(net "PE_RX4_DR0_N")
		)
		(pad "E21" smd rect
			(at 12.519914 -1.949958 90)
			(size 0.508 2.0066)
			(layers "F.Cu" "F.Mask" "F.Paste")
			(net "PE_RX4_DR0_P")
		)
		(pad "E22" smd rect
			(at 13.320014 -1.949958 90)
			(size 0.508 2.0066)
			(layers "F.Cu" "F.Mask" "F.Paste")
			(net "GND")
		)
		(pad "E23" smd rect
			(at 14.120114 -1.949958 90)
			(size 0.508 2.0066)
			(layers "F.Cu" "F.Mask" "F.Paste")
			(net "SCL_DR0_R")
		)
		(pad "E24" smd rect
			(at 14.91996 -1.949958 90)
			(size 0.508 2.0066)
			(layers "F.Cu" "F.Mask" "F.Paste")
			(net "SDA_DR0_R")
		)
		(pad "E25" smd rect
			(at 15.72006 -1.949958 90)
			(size 0.508 2.0066)
			(layers "F.Cu" "F.Mask" "F.Paste")
			(net "DUALPORTEN#0")
		)
		(pad "P1" smd rect
			(at -1.905 0.824992 90)
			(size 0.6604 2.0574)
			(layers "F.Cu" "F.Mask" "F.Paste")
			(net "Net_20")
		)
		(pad "P2" smd rect
			(at -0.635 0.824992 90)
			(size 0.6604 2.0574)
			(layers "F.Cu" "F.Mask" "F.Paste")
			(net "Net_19")
		)
		(pad "P3" smd rect
			(at 0.635 0.824992 90)
			(size 0.6604 2.0574)
			(layers "F.Cu" "F.Mask" "F.Paste")
			(net "Net_18")
		)
		(pad "P4" smd rect
			(at 1.905 0.824992 90)
			(size 0.6604 2.0574)
			(layers "F.Cu" "F.Mask" "F.Paste")
			(net "SSD0_CLK0_OE_N")
		)
		(pad "P5" smd rect
			(at 3.175 0.824992 90)
			(size 0.6604 2.0574)
			(layers "F.Cu" "F.Mask" "F.Paste")
			(net "GND")
		)
		(pad "P6" smd rect
			(at 4.445 0.824992 90)
			(size 0.6604 2.0574)
			(layers "F.Cu" "F.Mask" "F.Paste")
			(net "GND")
		)
		(pad "P7" smd rect
			(at 5.715 0.824992 90)
			(size 0.6604 2.0574)
			(layers "F.Cu" "F.Mask" "F.Paste")
			(net "Net_14")
		)
		(pad "P8" smd rect
			(at 6.985 0.824992 90)
			(size 0.6604 2.0574)
			(layers "F.Cu" "F.Mask" "F.Paste")
			(net "Net_13")
		)
		(pad "P9" smd rect
			(at 8.255 0.824992 90)
			(size 0.6604 2.0574)
			(layers "F.Cu" "F.Mask" "F.Paste")
			(net "Net_12")
		)
		(pad "P10" smd rect
			(at 9.525 0.824992 90)
			(size 0.6604 2.0574)
			(layers "F.Cu" "F.Mask" "F.Paste")
			(net "SSD_PRSNT_NET0")
		)
		(pad "P11" smd rect
			(at 10.795 0.824992 90)
			(size 0.6604 2.0574)
			(layers "F.Cu" "F.Mask" "F.Paste")
			(net "SSD_ACT_DR0")
		)
		(pad "P12" smd rect
			(at 12.065 0.824992 90)
			(size 0.6604 2.0574)
			(layers "F.Cu" "F.Mask" "F.Paste")
			(net "GND")
		)
		(pad "P13" smd rect
			(at 13.335 0.824992 90)
			(size 0.6604 2.0574)
			(layers "F.Cu" "F.Mask" "F.Paste")
			(net "12V_PRECH_SSD0")
		)
		(pad "P14" smd rect
			(at 14.605 0.824992 90)
			(size 0.6604 2.0574)
			(layers "F.Cu" "F.Mask" "F.Paste")
			(net "P12V_SSD0")
		)
		(pad "P15" smd rect
			(at 15.875 0.824992 90)
			(size 0.6604 2.0574)
			(layers "F.Cu" "F.Mask" "F.Paste")
			(net "P12V_SSD0")
		)
		(pad "PTH1" thru_hole oval
			(at -21.999956 2.350008 90)
			(size 1.524 2.6162)
			(drill oval 0.8128 1.905)
			(layers "*.Cu" "*.Mask")
			(remove_unused_layers no)
			(net "Net_29")
			(clearance 0.1524)
			(thermal_gap 0.1524)
		)
		(pad "PTH2" thru_hole oval
			(at 21.999956 2.350008 90)
			(size 1.524 2.6162)
			(drill oval 0.8128 1.905)
			(layers "*.Cu" "*.Mask")
			(remove_unused_layers no)
			(net "Net_10")
			(clearance 0.1524)
			(thermal_gap 0.1524)
		)
		(pad "S1" smd rect
			(at -15.875 0.824992 90)
			(size 0.6604 2.0574)
			(layers "F.Cu" "F.Mask" "F.Paste")
			(net "GND")
		)
		(pad "S2" smd rect
			(at -14.605 0.824992 90)
			(size 0.6604 2.0574)
			(layers "F.Cu" "F.Mask" "F.Paste")
			(net "Net_28")
		)
		(pad "S3" smd rect
			(at -13.335 0.824992 90)
			(size 0.6604 2.0574)
			(layers "F.Cu" "F.Mask" "F.Paste")
			(net "Net_27")
		)
		(pad "S4" smd rect
			(at -12.065 0.824992 90)
			(size 0.6604 2.0574)
			(layers "F.Cu" "F.Mask" "F.Paste")
			(net "GND")
		)
		(pad "S5" smd rect
			(at -10.795 0.824992 90)
			(size 0.6604 2.0574)
			(layers "F.Cu" "F.Mask" "F.Paste")
			(net "Net_26")
		)
		(pad "S6" smd rect
			(at -9.525 0.824992 90)
			(size 0.6604 2.0574)
			(layers "F.Cu" "F.Mask" "F.Paste")
			(net "Net_25")
		)
		(pad "S7" smd rect
			(at -8.255 0.824992 90)
			(size 0.6604 2.0574)
			(layers "F.Cu" "F.Mask" "F.Paste")
			(net "GND")
		)
		(pad "S8" smd rect
			(at -7.480046 -1.949958 90)
			(size 0.508 2.0066)
			(layers "F.Cu" "F.Mask" "F.Paste")
			(net "GND")
		)
		(pad "S9" smd rect
			(at -6.679946 -1.949958 90)
			(size 0.508 2.0066)
			(layers "F.Cu" "F.Mask" "F.Paste")
			(net "Net_23")
		)
		(pad "S10" smd rect
			(at -5.8801 -1.949958 90)
			(size 0.508 2.0066)
			(layers "F.Cu" "F.Mask" "F.Paste")
			(net "Net_22")
		)
		(pad "S11" smd rect
			(at -5.08 -1.949958 90)
			(size 0.508 2.0066)
			(layers "F.Cu" "F.Mask" "F.Paste")
			(net "GND")
		)
		(pad "S12" smd rect
			(at -4.2799 -1.949958 90)
			(size 0.508 2.0066)
			(layers "F.Cu" "F.Mask" "F.Paste")
			(net "Net_21")
		)
		(pad "S13" smd rect
			(at -3.480054 -1.949958 90)
			(size 0.508 2.0066)
			(layers "F.Cu" "F.Mask" "F.Paste")
			(net "Net_16")
		)
		(pad "S14" smd rect
			(at -2.679954 -1.949958 90)
			(size 0.508 2.0066)
			(layers "F.Cu" "F.Mask" "F.Paste")
			(net "GND")
		)
		(pad "S15" smd rect
			(at -1.880108 -1.949958 90)
			(size 0.508 2.0066)
			(layers "F.Cu" "F.Mask" "F.Paste")
			(net "Net_15")
		)
		(pad "S16" smd rect
			(at -1.080008 -1.949958 90)
			(size 0.508 2.0066)
			(layers "F.Cu" "F.Mask" "F.Paste")
			(net "GND")
		)
		(pad "S17" smd rect
			(at -0.279908 -1.949958 90)
			(size 0.508 2.0066)
			(layers "F.Cu" "F.Mask" "F.Paste")
			(net "PE_TX2_DR0_N")
		)
		(pad "S18" smd rect
			(at 0.519938 -1.949958 90)
			(size 0.508 2.0066)
			(layers "F.Cu" "F.Mask" "F.Paste")
			(net "PE_TX2_DR0_P")
		)
		(pad "S19" smd rect
			(at 1.320038 -1.949958 90)
			(size 0.508 2.0066)
			(layers "F.Cu" "F.Mask" "F.Paste")
			(net "GND")
		)
		(pad "S20" smd rect
			(at 2.119884 -1.949958 90)
			(size 0.508 2.0066)
			(layers "F.Cu" "F.Mask" "F.Paste")
			(net "PE_RX2_DR0_N")
		)
		(pad "S21" smd rect
			(at 2.919984 -1.949958 90)
			(size 0.508 2.0066)
			(layers "F.Cu" "F.Mask" "F.Paste")
			(net "PE_RX2_DR0_P")
		)
		(pad "S22" smd rect
			(at 3.720084 -1.949958 90)
			(size 0.508 2.0066)
			(layers "F.Cu" "F.Mask" "F.Paste")
			(net "GND")
		)
		(pad "S23" smd rect
			(at 4.51993 -1.949958 90)
			(size 0.508 2.0066)
			(layers "F.Cu" "F.Mask" "F.Paste")
			(net "PE_TX3_DR0_N")
		)
		(pad "S24" smd rect
			(at 5.32003 -1.949958 90)
			(size 0.508 2.0066)
			(layers "F.Cu" "F.Mask" "F.Paste")
			(net "PE_TX3_DR0_P")
		)
		(pad "S25" smd rect
			(at 6.119876 -1.949958 90)
			(size 0.508 2.0066)
			(layers "F.Cu" "F.Mask" "F.Paste")
			(net "GND")
		)
		(pad "S26" smd rect
			(at 6.919976 -1.949958 90)
			(size 0.508 2.0066)
			(layers "F.Cu" "F.Mask" "F.Paste")
			(net "PE_RX3_DR0_N")
		)
		(pad "S27" smd rect
			(at 7.720076 -1.949958 90)
			(size 0.508 2.0066)
			(layers "F.Cu" "F.Mask" "F.Paste")
			(net "PE_RX3_DR0_P")
		)
		(pad "S28" smd rect
			(at 8.519922 -1.949958 90)
			(size 0.508 2.0066)
			(layers "F.Cu" "F.Mask" "F.Paste")
			(net "GND")
		)
		(zone
			(layers "F.Cu" "B.Cu" "In1.Cu" "In2.Cu" "In3.Cu" "In4.Cu" "In5.Cu" "In6.Cu")
			(hatch none 0.5)
			(connect_pads
				(clearance 0)
			)
			(min_thickness 0.25)
			(keepout
				(tracks not_allowed)
				(vias allowed)
				(pads allowed)
				(copperpour not_allowed)
				(footprints allowed)
			)
			(placement
				(enabled no)
				(sheetname "")
			)
			(fill
				(thermal_gap 0.5)
				(thermal_bridge_width 0.5)
				(island_removal_mode 0)
			)
			(polygon
				(pts
					(arc
						(start 227.381816 -498.670072)
						(mid 224.918016 -498.670072)
						(end 227.381816 -498.670072)
					)
				)
			)
		)
		(zone
			(layers "F.Cu" "B.Cu" "In1.Cu" "In2.Cu" "In3.Cu" "In4.Cu" "In5.Cu" "In6.Cu")
			(hatch none 0.5)
			(connect_pads
				(clearance 0)
			)
			(min_thickness 0.25)
			(keepout
				(tracks not_allowed)
				(vias allowed)
				(pads allowed)
				(copperpour not_allowed)
				(footprints allowed)
			)
			(placement
				(enabled no)
				(sheetname "")
			)
			(fill
				(thermal_gap 0.5)
				(thermal_bridge_width 0.5)
				(island_removal_mode 0)
			)
			(polygon
				(pts
					(arc
						(start 227.381816 -460.670148)
						(mid 224.918016 -460.670148)
						(end 227.381816 -460.670148)
					)
				)
			)
		)
	)
)
